(kicad_pcb
	(version 20260206)
	(generator "pcbnew")
	(generator_version "10.0")
	(general
		(thickness 1.6)
		(legacy_teardrops no)
	)
	(paper "A4")
	(title_block
		(title "Bryce Canyon_F.DPB_16315-1-OCP.brd")
		(comment 1 "Bryce Canyon / footprints 894-901 of 2223")
	)
	(layers
		(0 "F.Cu" signal "TOP")
		(4 "In1.Cu" signal "L2GND")
		(6 "In2.Cu" signal "L3")
		(8 "In3.Cu" signal "L4GND")
		(10 "In4.Cu" signal "L5")
		(12 "In5.Cu" signal "L6VCC")
		(14 "In6.Cu" signal "L7VCC")
		(16 "In7.Cu" signal "L8")
		(18 "In8.Cu" signal "L9GND")
		(20 "In9.Cu" signal "L10")
		(22 "In10.Cu" signal "L11GND")
		(2 "B.Cu" signal "BOTTOM")
		(9 "F.Adhes" user "F.Adhesive")
		(11 "B.Adhes" user "B.Adhesive")
		(13 "F.Paste" user "Package Geometry/Pastemask Top")
		(15 "B.Paste" user "Package Geometry/Pastemask Bottom")
		(5 "F.SilkS" user "Ref Des/Silkscreen Top")
		(7 "B.SilkS" user "Ref Des/Silkscreen Bottom")
		(1 "F.Mask" user "Board Geometry/Soldermask Top")
		(3 "B.Mask" user "Board Geometry/Soldermask Bottom")
		(17 "Dwgs.User" user "User.Drawings")
		(19 "Cmts.User" user "User.Comments")
		(21 "Eco1.User" user "User.Eco1")
		(23 "Eco2.User" user "User.Eco2")
		(25 "Edge.Cuts" user "Board Geometry/Outline")
		(27 "Margin" user)
		(31 "F.CrtYd" user "Package Geometry/Place Bound Top")
		(29 "B.CrtYd" user "Package Geometry/Place Bound Bottom")
		(35 "F.Fab" user "Ref Des/Assembly Top")
		(33 "B.Fab" user "Ref Des/Assembly Bottom")
	)
	(footprint ""
		(layer "F.Cu")
		(at 477.2406 -163.068 180)
		(property "Reference" "R659"
			(at 0 0 180)
			(layer "F.SilkS")
			(hide yes)
			(effects
				(font
					(size 1.27 1.27)
				)
			)
		)
		(property "Value" "10KR2F-2-GP"
			(at 0.064008 -3.993896 180)
			(unlocked yes)
			(layer "F.Fab")
			(hide yes)
			(effects
				(font
					(size 1.016 1.016)
					(thickness 0.1524)
				)
			)
		)
		(property "Device Type" "R402H16"
			(at 0.064008 -5.517896 180)
			(unlocked yes)
			(layer "F.Fab")
			(hide yes)
			(effects
				(font
					(size 1.016 1.016)
					(thickness 0.1524)
				)
			)
		)
		(duplicate_pad_numbers_are_jumpers no)
		(fp_line
			(start 0.508 -0.9398)
			(end -0.508 -0.9398)
			(stroke
				(width 0.1524)
				(type default)
			)
			(layer "F.SilkS")
		)
		(fp_line
			(start -0.508 -0.9398)
			(end -0.508 0.9398)
			(stroke
				(width 0.1524)
				(type default)
			)
			(layer "F.SilkS")
		)
		(fp_rect
			(start -0.508 0.9398)
			(end 0.508 -0.9398)
			(stroke
				(width 0)
				(type default)
			)
			(fill no)
			(layer "F.CrtYd")
		)
		(fp_rect
			(start -0.508 0.9398)
			(end 0.508 -0.9398)
			(stroke
				(width 0)
				(type default)
			)
			(fill no)
			(layer "F.Fab")
		)
		(pad "1" smd custom
			(at 0 -0.4445 180)
			(size 0.1397 0.1397)
			(layers "F.Cu" "F.Mask" "F.Paste")
			(net "P3V3_STBY_A")
			(options
				(clearance outline)
				(anchor circle)
			)
			(primitives
				(gr_poly
					(pts
						(arc
							(start -0.1778 -0.2794)
							(mid -0.249642 -0.249642)
							(end -0.2794 -0.1778)
						)
						(arc
							(start -0.2794 0.1778)
							(mid -0.249642 0.249642)
							(end -0.1778 0.2794)
						)
						(arc
							(start 0.1778 0.2794)
							(mid 0.249642 0.249642)
							(end 0.2794 0.1778)
						)
						(arc
							(start 0.2794 -0.1778)
							(mid 0.249642 -0.249642)
							(end 0.1778 -0.2794)
						)
					)
					(width 0)
					(fill yes)
				)
			)
		)
		(pad "2" smd custom
			(at 0 0.4445 180)
			(size 0.1397 0.1397)
			(layers "F.Cu" "F.Mask" "F.Paste")
			(net "HDD_PRSNT_23")
			(options
				(clearance outline)
				(anchor circle)
			)
			(primitives
				(gr_poly
					(pts
						(arc
							(start -0.1778 -0.2794)
							(mid -0.249642 -0.249642)
							(end -0.2794 -0.1778)
						)
						(arc
							(start -0.2794 0.1778)
							(mid -0.249642 0.249642)
							(end -0.1778 0.2794)
						)
						(arc
							(start 0.1778 0.2794)
							(mid 0.249642 0.249642)
							(end 0.2794 0.1778)
						)
						(arc
							(start 0.2794 -0.1778)
							(mid 0.249642 -0.249642)
							(end 0.1778 -0.2794)
						)
					)
					(width 0)
					(fill yes)
				)
			)
		)
	)
	(footprint ""
		(layer "F.Cu")
		(at 202.300078 -183.805576)
		(property "Reference" ""
			(at 0 0 0)
			(layer "F.SilkS")
			(hide yes)
			(effects
				(font
					(size 1.27 1.27)
				)
			)
		)
		(property "Value" "*"
			(at -8.398764 -8.057642 0)
			(unlocked yes)
			(layer "F.Fab")
			(hide yes)
			(effects
				(font
					(size 1.016 1.016)
					(thickness 0.1524)
				)
			)
		)
		(duplicate_pad_numbers_are_jumpers no)
		(fp_poly
			(pts
				(arc
					(start 7.3152 0)
					(mid 0 7.3152)
					(end -7.3152 0)
				)
				(arc
					(start -7.3152 -5.9944)
					(mid 0 -13.3096)
					(end 7.3152 -5.9944)
				)
			)
			(stroke
				(width 0)
				(type default)
			)
			(fill no)
			(layer "B.CrtYd")
		)
		(fp_poly
			(pts
				(arc
					(start 7.3152 0)
					(mid 0 7.3152)
					(end -7.3152 0)
				)
				(arc
					(start -7.3152 -5.9944)
					(mid 0 -13.3096)
					(end 7.3152 -5.9944)
				)
			)
			(stroke
				(width 0)
				(type default)
			)
			(fill no)
			(layer "F.CrtYd")
		)
		(fp_poly
			(pts
				(arc
					(start 7.3152 0)
					(mid 0 7.3152)
					(end -7.3152 0)
				)
				(arc
					(start -7.3152 -5.9944)
					(mid 0 -13.3096)
					(end 7.3152 -5.9944)
				)
			)
			(stroke
				(width 0)
				(type default)
			)
			(fill no)
			(layer "B.Fab")
		)
		(fp_poly
			(pts
				(arc
					(start 7.3152 0)
					(mid 0 7.3152)
					(end -7.3152 0)
				)
				(arc
					(start -7.3152 -5.9944)
					(mid 0 -13.3096)
					(end 7.3152 -5.9944)
				)
			)
			(stroke
				(width 0)
				(type default)
			)
			(fill no)
			(layer "F.Fab")
		)
		(pad "1" thru_hole oval
			(at 0 0)
			(size 14.0208 20.0152)
			(drill 0.0254
				(offset 0 -2.9972)
			)
			(layers "*.Cu" "*.Mask")
			(remove_unused_layers no)
			(net "Net_67")
			(clearance -1.002284)
			(thermal_gap 0.1524)
			(padstack
				(mode front_inner_back)
				(layer "Inner"
					(shape custom)
					(size 2.928012 2.928012)
					(options
						(anchor circle)
					)
					(primitives
						(gr_poly
							(pts
								(arc
									(start 4.571746 -2.084324)
									(mid 0.000333 7.430372)
									(end -4.571492 -2.084324)
								)
								(arc
									(start -4.571492 -2.084324)
									(mid -3.570296 -3.611977)
									(end -2.875026 -5.30098)
								)
								(arc
									(start -2.875026 -5.30098)
									(mid 0.000217 -7.43089)
									(end 2.87528 -5.30098)
								)
								(arc
									(start 2.87528 -5.30098)
									(mid 3.570511 -3.611956)
									(end 4.571746 -2.084324)
								)
							)
							(width 0)
							(fill yes)
						)
					)
					(clearance 0.1524)
				)
				(layer "B.Cu"
					(shape oval)
					(size 14.0208 20.0152)
					(offset 0 -2.9972)
					(clearance -1.002284)
				)
			)
		)
		(zone
			(layers "F.Cu" "B.Cu" "In1.Cu" "In2.Cu" "In3.Cu" "In4.Cu" "In5.Cu" "In6.Cu"
				"In7.Cu" "In8.Cu" "In9.Cu" "In10.Cu"
			)
			(hatch none 0.5)
			(connect_pads
				(clearance 0)
			)
			(min_thickness 0.25)
			(keepout
				(tracks not_allowed)
				(vias allowed)
				(pads allowed)
				(copperpour not_allowed)
				(footprints allowed)
			)
			(placement
				(enabled no)
				(sheetname "")
			)
			(fill
				(thermal_gap 0.5)
				(thermal_bridge_width 0.5)
				(island_removal_mode 0)
			)
			(polygon
				(pts
					(arc
						(start 195.289678 -189.799976)
						(mid 202.300078 -196.810376)
						(end 209.310478 -189.799976)
					)
					(arc
						(start 209.310478 -183.805576)
						(mid 202.300078 -176.795176)
						(end 195.289678 -183.805576)
					)
				)
			)
		)
	)
	(footprint ""
		(layer "F.Cu")
		(at 80.24495 -127.254)
		(property "Reference" "R289"
			(at 0 0 0)
			(layer "F.SilkS")
			(hide yes)
			(effects
				(font
					(size 1.27 1.27)
				)
			)
		)
		(property "Value" "130R3F-GP"
			(at -0.0254 -2.5146 0)
			(unlocked yes)
			(layer "F.Fab")
			(hide yes)
			(effects
				(font
					(size 1.016 1.016)
					(thickness 0.1524)
				)
			)
		)
		(property "Device Type" "R603H22"
			(at -0.0254 -4.0386 0)
			(unlocked yes)
			(layer "F.Fab")
			(hide yes)
			(effects
				(font
					(size 1.016 1.016)
					(thickness 0.1524)
				)
			)
		)
		(duplicate_pad_numbers_are_jumpers no)
		(fp_line
			(start -0.4826 0)
			(end -0.2032 0)
			(stroke
				(width 0.2032)
				(type default)
			)
			(layer "F.SilkS")
		)
		(fp_line
			(start 0.2032 0)
			(end 0.4826 0)
			(stroke
				(width 0.2032)
				(type default)
			)
			(layer "F.SilkS")
		)
		(fp_rect
			(start -0.5842 1.3335)
			(end 0.5842 -1.3335)
			(stroke
				(width 0)
				(type default)
			)
			(fill no)
			(layer "F.CrtYd")
		)
		(fp_rect
			(start -0.5842 1.3335)
			(end 0.5842 -1.3335)
			(stroke
				(width 0)
				(type default)
			)
			(fill no)
			(layer "F.Fab")
		)
		(pad "1" smd custom
			(at 0 -0.762)
			(size 0.2159 0.2159)
			(layers "F.Cu" "F.Mask" "F.Paste")
			(net "P5V_A_1")
			(options
				(clearance outline)
				(anchor circle)
			)
			(primitives
				(gr_poly
					(pts
						(arc
							(start -0.3302 -0.4318)
							(mid -0.402042 -0.402042)
							(end -0.4318 -0.3302)
						)
						(arc
							(start -0.4318 0.3302)
							(mid -0.402042 0.402042)
							(end -0.3302 0.4318)
						)
						(arc
							(start 0.3302 0.4318)
							(mid 0.402042 0.402042)
							(end 0.4318 0.3302)
						)
						(arc
							(start 0.4318 -0.3302)
							(mid 0.402042 -0.402042)
							(end 0.3302 -0.4318)
						)
					)
					(width 0)
					(fill yes)
				)
			)
		)
		(pad "2" smd custom
			(at 0 0.762)
			(size 0.2159 0.2159)
			(layers "F.Cu" "F.Mask" "F.Paste")
			(net "FLT_HDD14")
			(options
				(clearance outline)
				(anchor circle)
			)
			(primitives
				(gr_poly
					(pts
						(arc
							(start -0.3302 -0.4318)
							(mid -0.402042 -0.402042)
							(end -0.4318 -0.3302)
						)
						(arc
							(start -0.4318 0.3302)
							(mid -0.402042 0.402042)
							(end -0.3302 0.4318)
						)
						(arc
							(start 0.3302 0.4318)
							(mid 0.402042 0.402042)
							(end 0.4318 0.3302)
						)
						(arc
							(start 0.4318 -0.3302)
							(mid 0.402042 -0.402042)
							(end 0.3302 -0.4318)
						)
					)
					(width 0)
					(fill yes)
				)
			)
		)
	)
	(footprint ""
		(layer "F.Cu")
		(at 113.175542 -280.879804)
		(property "Reference" "R213"
			(at 0 0 0)
			(layer "F.SilkS")
			(hide yes)
			(effects
				(font
					(size 1.27 1.27)
				)
			)
		)
		(property "Value" "4K7R2J-2-GP"
			(at 0.064008 -3.993896 0)
			(unlocked yes)
			(layer "F.Fab")
			(hide yes)
			(effects
				(font
					(size 1.016 1.016)
					(thickness 0.1524)
				)
			)
		)
		(property "Device Type" "R402H16"
			(at 0.064008 -5.517896 0)
			(unlocked yes)
			(layer "F.Fab")
			(hide yes)
			(effects
				(font
					(size 1.016 1.016)
					(thickness 0.1524)
				)
			)
		)
		(duplicate_pad_numbers_are_jumpers no)
		(fp_line
			(start -0.508 -0.9398)
			(end -0.508 0.9398)
			(stroke
				(width 0.1524)
				(type default)
			)
			(layer "F.SilkS")
		)
		(fp_line
			(start 0.508 -0.9398)
			(end -0.508 -0.9398)
			(stroke
				(width 0.1524)
				(type default)
			)
			(layer "F.SilkS")
		)
		(fp_rect
			(start -0.508 0.9398)
			(end 0.508 -0.9398)
			(stroke
				(width 0)
				(type default)
			)
			(fill no)
			(layer "F.CrtYd")
		)
		(fp_rect
			(start -0.508 0.9398)
			(end 0.508 -0.9398)
			(stroke
				(width 0)
				(type default)
			)
			(fill no)
			(layer "F.Fab")
		)
		(pad "1" smd custom
			(at 0 -0.4445)
			(size 0.1397 0.1397)
			(layers "F.Cu" "F.Mask" "F.Paste")
			(net "P12V_A")
			(options
				(clearance outline)
				(anchor circle)
			)
			(primitives
				(gr_poly
					(pts
						(arc
							(start -0.1778 -0.2794)
							(mid -0.249642 -0.249642)
							(end -0.2794 -0.1778)
						)
						(arc
							(start -0.2794 0.1778)
							(mid -0.249642 0.249642)
							(end -0.1778 0.2794)
						)
						(arc
							(start 0.1778 0.2794)
							(mid 0.249642 0.249642)
							(end 0.2794 0.1778)
						)
						(arc
							(start 0.2794 -0.1778)
							(mid 0.249642 -0.249642)
							(end 0.1778 -0.2794)
						)
					)
					(width 0)
					(fill yes)
				)
			)
		)
		(pad "2" smd custom
			(at 0 0.4445)
			(size 0.1397 0.1397)
			(layers "F.Cu" "F.Mask" "F.Paste")
			(net "SW_HDD_R3")
			(options
				(clearance outline)
				(anchor circle)
			)
			(primitives
				(gr_poly
					(pts
						(arc
							(start -0.1778 -0.2794)
							(mid -0.249642 -0.249642)
							(end -0.2794 -0.1778)
						)
						(arc
							(start -0.2794 0.1778)
							(mid -0.249642 0.249642)
							(end -0.1778 0.2794)
						)
						(arc
							(start 0.1778 0.2794)
							(mid 0.249642 0.249642)
							(end 0.2794 0.1778)
						)
						(arc
							(start 0.2794 -0.1778)
							(mid 0.249642 -0.249642)
							(end 0.1778 -0.2794)
						)
					)
					(width 0)
					(fill yes)
				)
			)
		)
	)
	(footprint ""
		(layer "F.Cu")
		(at 229.849934 6.500114)
		(property "Reference" ""
			(at 0 0 0)
			(layer "F.SilkS")
			(hide yes)
			(effects
				(font
					(size 1.27 1.27)
				)
			)
		)
		(property "Value" "*"
			(at -4.9911 1.5494 0)
			(unlocked yes)
			(layer "F.Fab")
			(hide yes)
			(effects
				(font
					(size 1.016 1.016)
					(thickness 0.1524)
				)
			)
		)
		(duplicate_pad_numbers_are_jumpers no)
		(fp_poly
			(pts
				(arc
					(start 4.064 0)
					(mid -4.064 0)
					(end 4.064 0)
				)
			)
			(stroke
				(width 0)
				(type default)
			)
			(fill no)
			(layer "B.CrtYd")
		)
		(fp_poly
			(pts
				(arc
					(start 4.064 0)
					(mid -4.064 0)
					(end 4.064 0)
				)
			)
			(stroke
				(width 0)
				(type default)
			)
			(fill no)
			(layer "F.CrtYd")
		)
		(fp_poly
			(pts
				(arc
					(start 4.064 0)
					(mid -4.064 0)
					(end 4.064 0)
				)
			)
			(stroke
				(width 0)
				(type default)
			)
			(fill no)
			(layer "B.Fab")
		)
		(fp_poly
			(pts
				(arc
					(start 4.064 0)
					(mid -4.064 0)
					(end 4.064 0)
				)
			)
			(stroke
				(width 0)
				(type default)
			)
			(fill no)
			(layer "F.Fab")
		)
		(pad "1" thru_hole circle
			(at 0 0)
			(size 7.5184 7.5184)
			(drill oval 6.223 4.2164)
			(layers "*.Cu" "*.Mask")
			(remove_unused_layers no)
			(net "Net_34")
			(clearance -1.143)
			(thermal_gap 0.1524)
			(padstack
				(mode front_inner_back)
				(layer "Inner"
					(shape oval)
					(size 4.9276 6.9342)
					(clearance 0.1524)
				)
				(layer "B.Cu"
					(shape circle)
					(size 7.5184 7.5184)
					(clearance -1.143)
				)
			)
		)
		(zone
			(layers "F.Cu" "B.Cu" "In1.Cu" "In2.Cu" "In3.Cu" "In4.Cu" "In5.Cu" "In6.Cu"
				"In7.Cu" "In8.Cu" "In9.Cu" "In10.Cu"
			)
			(hatch none 0.5)
			(connect_pads
				(clearance 0)
			)
			(min_thickness 0.25)
			(keepout
				(tracks not_allowed)
				(vias allowed)
				(pads allowed)
				(copperpour not_allowed)
				(footprints allowed)
			)
			(placement
				(enabled no)
				(sheetname "")
			)
			(fill
				(thermal_gap 0.5)
				(thermal_bridge_width 0.5)
				(island_removal_mode 0)
			)
			(polygon
				(pts
					(arc
						(start 233.609134 6.500114)
						(mid 226.090734 6.500114)
						(end 233.609134 6.500114)
					)
				)
			)
		)
	)
	(footprint ""
		(layer "F.Cu")
		(at 158.663386 -274.219416 90)
		(property "Reference" "C90"
			(at 0 0 90)
			(layer "F.SilkS")
			(hide yes)
			(effects
				(font
					(size 1.27 1.27)
				)
			)
		)
		(property "Value" "SCD01U16V1KX-GP"
			(at -2.8321 -1.7399 90)
			(unlocked yes)
			(layer "F.Fab")
			(hide yes)
			(effects
				(font
					(size 1.016 1.016)
					(thickness 0.1524)
				)
			)
		)
		(property "Device Type" "C0201H13"
			(at -2.8321 -3.2639 90)
			(unlocked yes)
			(layer "F.Fab")
			(hide yes)
			(effects
				(font
					(size 1.016 1.016)
					(thickness 0.1524)
				)
			)
		)
		(duplicate_pad_numbers_are_jumpers no)
		(fp_rect
			(start -0.2794 0.6477)
			(end 0.2794 -0.6477)
			(stroke
				(width 0)
				(type default)
			)
			(fill no)
			(layer "F.CrtYd")
		)
		(fp_rect
			(start -0.2794 0.6477)
			(end 0.2794 -0.6477)
			(stroke
				(width 0)
				(type default)
			)
			(fill no)
			(layer "F.Fab")
		)
		(pad "1" smd custom
			(at 0 -0.2794 90)
			(size 0.0762 0.0762)
			(layers "F.Cu" "F.Mask" "F.Paste")
			(net "SAS_HDD_RX_N4")
			(options
				(clearance outline)
				(anchor circle)
			)
			(primitives
				(gr_poly
					(pts
						(arc
							(start 0.1524 -0.127)
							(mid 0.137521 -0.162921)
							(end 0.1016 -0.1778)
						)
						(arc
							(start -0.1016 -0.1778)
							(mid -0.137521 -0.162921)
							(end -0.1524 -0.127)
						)
						(arc
							(start -0.1524 0.127)
							(mid -0.137521 0.162921)
							(end -0.1016 0.1778)
						)
						(arc
							(start 0.1016 0.1778)
							(mid 0.137521 0.162921)
							(end 0.1524 0.127)
						)
					)
					(width 0)
					(fill yes)
				)
			)
		)
		(pad "2" smd custom
			(at 0 0.2794 90)
			(size 0.0762 0.0762)
			(layers "F.Cu" "F.Mask" "F.Paste")
			(net "PHY_SCC_A_TO_DRV_A_4_DN")
			(options
				(clearance outline)
				(anchor circle)
			)
			(primitives
				(gr_poly
					(pts
						(arc
							(start 0.1524 -0.127)
							(mid 0.137521 -0.162921)
							(end 0.1016 -0.1778)
						)
						(arc
							(start -0.1016 -0.1778)
							(mid -0.137521 -0.162921)
							(end -0.1524 -0.127)
						)
						(arc
							(start -0.1524 0.127)
							(mid -0.137521 0.162921)
							(end -0.1016 0.1778)
						)
						(arc
							(start 0.1016 0.1778)
							(mid 0.137521 0.162921)
							(end 0.1524 0.127)
						)
					)
					(width 0)
					(fill yes)
				)
			)
		)
	)
	(footprint ""
		(layer "F.Cu")
		(at 443.8396 -298.704)
		(property "Reference" "TP52"
			(at 0 0 0)
			(layer "F.SilkS")
			(hide yes)
			(effects
				(font
					(size 1.27 1.27)
				)
			)
		)
		(property "Value" "TPAD32-GP"
			(at -0.0508 -1.6764 0)
			(unlocked yes)
			(layer "F.Fab")
			(hide yes)
			(effects
				(font
					(size 1.016 1.016)
					(thickness 0.1524)
				)
			)
		)
		(property "Device Type" "TPAD32"
			(at -0.0508 -3.2004 0)
			(unlocked yes)
			(layer "F.Fab")
			(hide yes)
			(effects
				(font
					(size 1.016 1.016)
					(thickness 0.1524)
				)
			)
		)
		(duplicate_pad_numbers_are_jumpers no)
		(fp_poly
			(pts
				(arc
					(start 0.4064 0)
					(mid -0.4064 0)
					(end 0.4064 0)
				)
			)
			(stroke
				(width 0)
				(type default)
			)
			(fill no)
			(layer "F.CrtYd")
		)
		(fp_poly
			(pts
				(arc
					(start 0.7112 0)
					(mid -0.7112 0)
					(end 0.7112 0)
				)
			)
			(stroke
				(width 0)
				(type default)
			)
			(fill no)
			(layer "F.Fab")
		)
		(pad "1" smd circle
			(at 0 0)
			(size 0.8128 0.8128)
			(layers "F.Cu" "F.Mask" "F.Paste")
			(net "ACT_HDD_10")
		)
	)
	(footprint ""
		(layer "F.Cu")
		(at 272.542 -359.504996 180)
		(property "Reference" "VIA33"
			(at 0 0 180)
			(layer "F.SilkS")
			(hide yes)
			(effects
				(font
					(size 1.27 1.27)
				)
			)
		)
		(property "Value" "100OHM-8L-1D6MM-L18L16-GP"
			(at -3.7211 -4.5085 180)
			(unlocked yes)
			(layer "F.Fab")
			(hide yes)
			(effects
				(font
					(size 1.016 1.016)
					(thickness 0.1524)
				)
			)
		)
		(property "Device Type" "VIA-PCIE-4P-394076"
			(at -3.7211 -6.0325 180)
			(unlocked yes)
			(layer "F.Fab")
			(hide yes)
			(effects
				(font
					(size 1.016 1.016)
					(thickness 0.1524)
				)
			)
		)
		(duplicate_pad_numbers_are_jumpers no)
		(fp_rect
			(start -1.9685 0.381)
			(end 1.9685 -0.381)
			(stroke
				(width 0)
				(type default)
			)
			(fill no)
			(layer "F.CrtYd")
		)
		(fp_rect
			(start -1.9685 0.381)
			(end 1.9685 -0.381)
			(stroke
				(width 0)
				(type default)
			)
			(fill no)
			(layer "F.Fab")
		)
		(pad "1" thru_hole circle
			(at -1.5875 0 180)
			(size 0.508 0.508)
			(drill 0.254)
			(layers "*.Cu" "*.Mask")
			(remove_unused_layers no)
			(net "GND")
			(clearance 0.127)
			(thermal_gap 0.127)
		)
		(pad "2" thru_hole circle
			(at -0.5715 0 180)
			(size 0.508 0.508)
			(drill 0.254)
			(layers "*.Cu" "*.Mask")
			(remove_unused_layers no)
			(net "PHY_SCC_A_TO_DRV_A_0_DP")
			(clearance 0.127)
			(thermal_gap 0.127)
		)
		(pad "3" thru_hole circle
			(at 0.5715 0 180)
			(size 0.508 0.508)
			(drill 0.254)
			(layers "*.Cu" "*.Mask")
			(remove_unused_layers no)
			(net "PHY_SCC_A_TO_DRV_A_0_DN")
			(clearance 0.127)
			(thermal_gap 0.127)
		)
		(pad "4" thru_hole circle
			(at 1.5875 0 180)
			(size 0.508 0.508)
			(drill 0.254)
			(layers "*.Cu" "*.Mask")
			(remove_unused_layers no)
			(net "GND")
			(clearance 0.127)
			(thermal_gap 0.127)
		)
	)
)
